# TIMECARD (Time Appliance Project (Time Card)) — schematic netlist excerpt (pin names and nets, part order shuffled) for the footprints in the layout excerpt that follows; sources: Cadence DE-HDL packaged netlist, KiCad conversion of R4006-B0001-02_R01.brd

C188  CAPACITOR  0.1UF 25V 10%  pkg SMC_0402R_H022  page 30 : \1\ = XP1R2V_VIN ; \2\ = SG
R170  RESISTOR  10KOHM 1%  pkg SMC_0402R_H016  page 25 : \1\ = XP3R3V_FPGA ; \2\ = FPGA_IO_0

(kicad_pcb
	(version 20260206)
	(generator "pcbnew")
	(generator_version "10.0")
	(general
		(thickness 1.6)
		(legacy_teardrops no)
	)
	(paper "A4")
	(title_block
		(title "timecard-production-celestica-r4006 — R4006-B0001-02_R01.brd")
		(comment 1 "Time Appliance Project (Time Card) / footprints 274-275 of 1113")
	)
	(layers
		(0 "F.Cu" signal "TOP")
		(4 "In1.Cu" signal "L02_GND1")
		(6 "In2.Cu" signal "L03_SIG1")
		(8 "In3.Cu" signal "L04_GND2")
		(10 "In4.Cu" signal "L05_VCC1")
		(12 "In5.Cu" signal "L06_VCC2")
		(14 "In6.Cu" signal "L07_GND3")
		(16 "In7.Cu" signal "L08_SIG2")
		(18 "In8.Cu" signal "L09_GND4")
		(2 "B.Cu" signal "BOTTOM")
		(9 "F.Adhes" user "F.Adhesive")
		(11 "B.Adhes" user "B.Adhesive")
		(13 "F.Paste" user "Package Geometry/Pastemask Top")
		(15 "B.Paste" user "Package Geometry/Pastemask Bottom")
		(5 "F.SilkS" user "Ref Des/Silkscreen Top")
		(7 "B.SilkS" user "Ref Des/Silkscreen Bottom")
		(1 "F.Mask" user "Board Geometry/Soldermask Top")
		(3 "B.Mask" user "Board Geometry/Soldermask Bottom")
		(17 "Dwgs.User" user "User.Drawings")
		(19 "Cmts.User" user "User.Comments")
		(21 "Eco1.User" user "User.Eco1")
		(23 "Eco2.User" user "User.Eco2")
		(25 "Edge.Cuts" user "Board Geometry/Outline")
		(27 "Margin" user)
		(31 "F.CrtYd" user "Package Geometry/Place Bound Top")
		(29 "B.CrtYd" user "Package Geometry/Place Bound Bottom")
		(35 "F.Fab" user "Ref Des/Assembly Top")
		(33 "B.Fab" user "Ref Des/Assembly Bottom")
	)
	(footprint ""
		(layer "F.Cu")
		(at 101.0412 -64.2874 -90)
		(property "Reference" "R170"
			(at 2.6924 -0.85217 90)
			(unlocked yes)
			(layer "F.SilkS")
			(effects
				(font
					(size 0.7874 0.5842)
					(thickness 0.1524)
				)
			)
		)
		(property "Value" "VAL*"
			(at 0.02032 2.13233 270)
			(unlocked yes)
			(layer "F.Fab")
			(hide yes)
			(effects
				(font
					(size 0.7874 0.5842)
					(thickness 0.1524)
				)
			)
		)
		(property "Tolerance" "TOL*"
			(at 0.044704 3.05435 270)
			(unlocked yes)
			(layer "Cmts.User")
			(hide yes)
			(effects
				(font
					(size 0.7874 0.5842)
					(thickness 0.1524)
				)
			)
		)
		(property "User Part Number" "PARTNUM*"
			(at 0.02032 4.024884 270)
			(unlocked yes)
			(layer "Cmts.User")
			(hide yes)
			(effects
				(font
					(size 0.7874 0.5842)
					(thickness 0.1524)
				)
			)
		)
		(property "Device Type" "RESISTOR-G155-11002-01,10KOHM,A"
			(at 0.008382 1.210564 270)
			(unlocked yes)
			(layer "F.Fab")
			(hide yes)
			(effects
				(font
					(size 0.7874 0.5842)
					(thickness 0.1524)
				)
			)
		)
		(duplicate_pad_numbers_are_jumpers no)
		(fp_line
			(start -1.143 0.5588)
			(end 1.143 0.5588)
			(stroke
				(width 0.1)
				(type default)
			)
			(layer "F.SilkS")
		)
		(fp_line
			(start 1.143 0.5588)
			(end 1.143 -0.5588)
			(stroke
				(width 0.1)
				(type default)
			)
			(layer "F.SilkS")
		)
		(fp_line
			(start -1.143 -0.5588)
			(end -1.143 0.5588)
			(stroke
				(width 0.1)
				(type default)
			)
			(layer "F.SilkS")
		)
		(fp_line
			(start 1.143 -0.5588)
			(end -1.143 -0.5588)
			(stroke
				(width 0.1)
				(type default)
			)
			(layer "F.SilkS")
		)
		(fp_rect
			(start -1.143 0.5588)
			(end 1.143 -0.5588)
			(stroke
				(width 0)
				(type default)
			)
			(fill no)
			(layer "F.CrtYd")
		)
		(fp_line
			(start -0.508 0.3048)
			(end 0.508 0.3048)
			(stroke
				(width 0.1)
				(type default)
			)
			(layer "F.Fab")
		)
		(fp_line
			(start 0.508 0.3048)
			(end 0.508 -0.3048)
			(stroke
				(width 0.1)
				(type default)
			)
			(layer "F.Fab")
		)
		(fp_line
			(start -0.508 -0.3048)
			(end -0.508 0.3048)
			(stroke
				(width 0.1)
				(type default)
			)
			(layer "F.Fab")
		)
		(fp_line
			(start 0.508 -0.3048)
			(end -0.508 -0.3048)
			(stroke
				(width 0.1)
				(type default)
			)
			(layer "F.Fab")
		)
		(pad "1" smd rect
			(at -0.5334 0 270)
			(size 0.7112 0.6096)
			(layers "F.Cu" "F.Mask" "F.Paste")
			(net "XP3R3V_FPGA")
		)
		(pad "2" smd rect
			(at 0.5334 0 270)
			(size 0.7112 0.6096)
			(layers "F.Cu" "F.Mask" "F.Paste")
			(net "FPGA_IO_0")
		)
		(zone
			(layer "F.Cu")
			(hatch none 0.5)
			(connect_pads
				(clearance 0)
			)
			(min_thickness 0.25)
			(keepout
				(tracks allowed)
				(vias not_allowed)
				(pads allowed)
				(copperpour not_allowed)
				(footprints allowed)
			)
			(placement
				(enabled no)
				(sheetname "")
			)
			(fill
				(thermal_gap 0.5)
				(thermal_bridge_width 0.5)
				(island_removal_mode 0)
			)
			(polygon
				(pts
					(xy 100.7364 -64.3636) (xy 100.7364 -64.2112) (xy 101.346 -64.2112) (xy 101.346 -64.3636)
				)
			)
		)
	)
	(footprint ""
		(layer "F.Cu")
		(at 96.4438 -75.946 -90)
		(property "Reference" "C188"
			(at -19.177 27.82443 90)
			(unlocked yes)
			(layer "F.SilkS")
			(effects
				(font
					(size 0.7874 0.5842)
					(thickness 0.1524)
				)
			)
		)
		(property "Value" "VAL*"
			(at 0.0762 2.067306 270)
			(unlocked yes)
			(layer "F.Fab")
			(hide yes)
			(effects
				(font
					(size 0.7874 0.5842)
					(thickness 0.1524)
				)
			)
		)
		(property "Tolerance" "TOL*"
			(at 0.0762 3.032506 270)
			(unlocked yes)
			(layer "Cmts.User")
			(hide yes)
			(effects
				(font
					(size 0.7874 0.5842)
					(thickness 0.1524)
				)
			)
		)
		(property "User Part Number" "PARTNUM*"
			(at 0.1016 4.023106 270)
			(unlocked yes)
			(layer "Cmts.User")
			(hide yes)
			(effects
				(font
					(size 0.7874 0.5842)
					(thickness 0.1524)
				)
			)
		)
		(property "Device Type" "CAPACITOR-G105-0B104-EK,0.1UF,A"
			(at 0.0508 1.127506 270)
			(unlocked yes)
			(layer "F.Fab")
			(hide yes)
			(effects
				(font
					(size 0.7874 0.5842)
					(thickness 0.1524)
				)
			)
		)
		(duplicate_pad_numbers_are_jumpers no)
		(fp_line
			(start -1.143 0.5588)
			(end 1.143 0.5588)
			(stroke
				(width 0.1)
				(type default)
			)
			(layer "F.SilkS")
		)
		(fp_line
			(start 1.143 0.5588)
			(end 1.143 -0.5588)
			(stroke
				(width 0.1)
				(type default)
			)
			(layer "F.SilkS")
		)
		(fp_line
			(start -1.143 -0.5588)
			(end -1.143 0.5588)
			(stroke
				(width 0.1)
				(type default)
			)
			(layer "F.SilkS")
		)
		(fp_line
			(start 1.143 -0.5588)
			(end -1.143 -0.5588)
			(stroke
				(width 0.1)
				(type default)
			)
			(layer "F.SilkS")
		)
		(fp_rect
			(start -1.143 0.5588)
			(end 1.143 -0.5588)
			(stroke
				(width 0)
				(type default)
			)
			(fill no)
			(layer "F.CrtYd")
		)
		(fp_line
			(start -0.508 0.3048)
			(end 0.508 0.3048)
			(stroke
				(width 0.1)
				(type default)
			)
			(layer "F.Fab")
		)
		(fp_line
			(start 0.508 0.3048)
			(end 0.508 -0.3048)
			(stroke
				(width 0.1)
				(type default)
			)
			(layer "F.Fab")
		)
		(fp_line
			(start -0.508 -0.3048)
			(end -0.508 0.3048)
			(stroke
				(width 0.1)
				(type default)
			)
			(layer "F.Fab")
		)
		(fp_line
			(start 0.508 -0.3048)
			(end -0.508 -0.3048)
			(stroke
				(width 0.1)
				(type default)
			)
			(layer "F.Fab")
		)
		(pad "1" smd rect
			(at -0.5334 0 270)
			(size 0.7112 0.6096)
			(layers "F.Cu" "F.Mask" "F.Paste")
			(net "XP1R2V_VIN")
		)
		(pad "2" smd rect
			(at 0.5334 0 270)
			(size 0.7112 0.6096)
			(layers "F.Cu" "F.Mask" "F.Paste")
			(net "SG")
		)
		(zone
			(layer "F.Cu")
			(hatch none 0.5)
			(connect_pads
				(clearance 0)
			)
			(min_thickness 0.25)
			(keepout
				(tracks allowed)
				(vias not_allowed)
				(pads allowed)
				(copperpour not_allowed)
				(footprints allowed)
			)
			(placement
				(enabled no)
				(sheetname "")
			)
			(fill
				(thermal_gap 0.5)
				(thermal_bridge_width 0.5)
				(island_removal_mode 0)
			)
			(polygon
				(pts
					(xy 96.139 -76.0222) (xy 96.139 -75.8698) (xy 96.7486 -75.8698) (xy 96.7486 -76.0222)
				)
			)
		)
	)
)
